(kicad_pcb
	(version 20260206)
	(generator "pcbnew")
	(generator_version "10.0")
	(general
		(thickness 1.6)
		(legacy_teardrops no)
	)
	(paper "A4")
	(title_block
		(title "03242023_DA0F0TMBIJ0_F0T_Motherboard_J_brd_V01_OCP.brd")
		(comment 1 "Grand Teton / footprints 6105-6105 of 6105")
	)
	(layers
		(0 "F.Cu" signal "TOP")
		(4 "In1.Cu" signal "GND")
		(6 "In2.Cu" signal "IN1")
		(8 "In3.Cu" signal "GND1")
		(10 "In4.Cu" signal "IN2")
		(12 "In5.Cu" signal "GND2")
		(14 "In6.Cu" signal "IN3")
		(16 "In7.Cu" signal "GND3")
		(18 "In8.Cu" signal "VCC")
		(20 "In9.Cu" signal "VCC1")
		(22 "In10.Cu" signal "GND4")
		(24 "In11.Cu" signal "IN4")
		(26 "In12.Cu" signal "GND5")
		(28 "In13.Cu" signal "IN5")
		(30 "In14.Cu" signal "GND6")
		(32 "In15.Cu" signal "IN6")
		(34 "In16.Cu" signal "GND7")
		(2 "B.Cu" signal "BOTTOM")
		(9 "F.Adhes" user "F.Adhesive")
		(11 "B.Adhes" user "B.Adhesive")
		(13 "F.Paste" user "Package Geometry/Pastemask Top")
		(15 "B.Paste" user "Package Geometry/Pastemask Bottom")
		(5 "F.SilkS" user "Ref Des/Silkscreen Top")
		(7 "B.SilkS" user "Ref Des/Silkscreen Bottom")
		(1 "F.Mask" user "Board Geometry/Soldermask Top")
		(3 "B.Mask" user "Board Geometry/Soldermask Bottom")
		(17 "Dwgs.User" user "User.Drawings")
		(19 "Cmts.User" user "User.Comments")
		(21 "Eco1.User" user "User.Eco1")
		(23 "Eco2.User" user "User.Eco2")
		(25 "Edge.Cuts" user "Board Geometry/Outline")
		(27 "Margin" user)
		(31 "F.CrtYd" user "Package Geometry/Place Bound Top")
		(29 "B.CrtYd" user "Package Geometry/Place Bound Bottom")
		(35 "F.Fab" user "Ref Des/Assembly Top")
		(33 "B.Fab" user "Ref Des/Assembly Bottom")
	)
	(footprint ""
		(layer "B.Cu")
		(at 187.88888 -101.564948)
		(property "Reference" "R3347"
			(at 0 0 0)
			(layer "B.SilkS")
			(hide yes)
			(effects
				(font
					(size 1.27 1.27)
				)
				(justify mirror)
			)
		)
		(property "Value" ""
			(at 0 0 0)
			(layer "B.Fab")
			(effects
				(font
					(size 1.27 1.27)
				)
				(justify mirror)
			)
		)
		(duplicate_pad_numbers_are_jumpers no)
		(fp_line
			(start -1.2954 -0.5842)
			(end -1.2954 0.5842)
			(stroke
				(width 0.1524)
				(type default)
			)
			(layer "B.SilkS")
		)
		(fp_line
			(start -1.2954 0.5842)
			(end 1.2954 0.5842)
			(stroke
				(width 0.1524)
				(type default)
			)
			(layer "B.SilkS")
		)
		(fp_line
			(start 1.2954 -0.5842)
			(end -1.2954 -0.5842)
			(stroke
				(width 0.1524)
				(type default)
			)
			(layer "B.SilkS")
		)
		(fp_line
			(start 1.2954 0.5842)
			(end 1.2954 -0.5842)
			(stroke
				(width 0.1524)
				(type default)
			)
			(layer "B.SilkS")
		)
		(fp_line
			(start -1.1938 -0.406654)
			(end -1.1938 0.4064)
			(stroke
				(width 0.1)
				(type default)
			)
			(layer "B.Fab")
		)
		(fp_line
			(start -1.1938 0.4064)
			(end -0.8636 0.4064)
			(stroke
				(width 0.1)
				(type default)
			)
			(layer "B.Fab")
		)
		(fp_line
			(start -0.8636 -0.4572)
			(end -0.8636 -0.406654)
			(stroke
				(width 0.1)
				(type default)
			)
			(layer "B.Fab")
		)
		(fp_line
			(start -0.8636 -0.406654)
			(end -1.1938 -0.406654)
			(stroke
				(width 0.1)
				(type default)
			)
			(layer "B.Fab")
		)
		(fp_line
			(start -0.8636 0.4064)
			(end -0.8636 0.4572)
			(stroke
				(width 0.1)
				(type default)
			)
			(layer "B.Fab")
		)
		(fp_line
			(start -0.8636 0.4572)
			(end 0.8636 0.4572)
			(stroke
				(width 0.1)
				(type default)
			)
			(layer "B.Fab")
		)
		(fp_line
			(start 0.8636 -0.4572)
			(end -0.8636 -0.4572)
			(stroke
				(width 0.1)
				(type default)
			)
			(layer "B.Fab")
		)
		(fp_line
			(start 0.8636 -0.406654)
			(end 0.8636 -0.4572)
			(stroke
				(width 0.1)
				(type default)
			)
			(layer "B.Fab")
		)
		(fp_line
			(start 0.8636 0.4064)
			(end 1.1938 0.4064)
			(stroke
				(width 0.1)
				(type default)
			)
			(layer "B.Fab")
		)
		(fp_line
			(start 0.8636 0.4318)
			(end 0.8636 0.4064)
			(stroke
				(width 0.1)
				(type default)
			)
			(layer "B.Fab")
		)
		(fp_line
			(start 0.8636 0.4572)
			(end 0.8636 0.4318)
			(stroke
				(width 0.1)
				(type default)
			)
			(layer "B.Fab")
		)
		(fp_line
			(start 1.1938 -0.406654)
			(end 0.8636 -0.406654)
			(stroke
				(width 0.1)
				(type default)
			)
			(layer "B.Fab")
		)
		(fp_line
			(start 1.1938 0.4064)
			(end 1.1938 -0.406654)
			(stroke
				(width 0.1)
				(type default)
			)
			(layer "B.Fab")
		)
		(pad "1" smd rect
			(at 0.7366 0 270)
			(size 0.7112 0.8128)
			(layers "B.Cu" "B.Mask" "B.Paste")
			(net "P3V3_AUX")
		)
		(pad "2" smd rect
			(at -0.7366 0 270)
			(size 0.7112 0.8128)
			(layers "B.Cu" "B.Mask" "B.Paste")
			(net "P3V3_AUX_FPGA_VCCIO2")
		)
	)
)
